# S9S_MB_2U (Grand Teton) — schematic netlist excerpt (pin names and nets, part order shuffled) for the footprints in the layout excerpt that follows; sources: Cadence DE-HDL packaged netlist, KiCad conversion of 03242023_DA0F0TMBIJ0_F0T_Motherboard_J_brd_V01_OCP.brd

PR4236  Q_RES  0 5% CHIP  pkg 0402LF  page 278 : A = NC_PVCCD_HV_CPU0_ACSP8 ; B = GND
R885  Q_RES  33.2 1% CHIP  pkg 0402LF  page 114 : A = PWRGD_CHE_CPU0_DIMM1 ; B = PWRGD_FAIL_CPU0_EF

(kicad_pcb
	(version 20260206)
	(generator "pcbnew")
	(generator_version "10.0")
	(general
		(thickness 1.6)
		(legacy_teardrops no)
	)
	(paper "A4")
	(title_block
		(title "03242023_DA0F0TMBIJ0_F0T_Motherboard_J_brd_V01_OCP.brd")
		(comment 1 "Grand Teton / footprints 5697-5698 of 6105")
	)
	(layers
		(0 "F.Cu" signal "TOP")
		(4 "In1.Cu" signal "GND")
		(6 "In2.Cu" signal "IN1")
		(8 "In3.Cu" signal "GND1")
		(10 "In4.Cu" signal "IN2")
		(12 "In5.Cu" signal "GND2")
		(14 "In6.Cu" signal "IN3")
		(16 "In7.Cu" signal "GND3")
		(18 "In8.Cu" signal "VCC")
		(20 "In9.Cu" signal "VCC1")
		(22 "In10.Cu" signal "GND4")
		(24 "In11.Cu" signal "IN4")
		(26 "In12.Cu" signal "GND5")
		(28 "In13.Cu" signal "IN5")
		(30 "In14.Cu" signal "GND6")
		(32 "In15.Cu" signal "IN6")
		(34 "In16.Cu" signal "GND7")
		(2 "B.Cu" signal "BOTTOM")
		(9 "F.Adhes" user "F.Adhesive")
		(11 "B.Adhes" user "B.Adhesive")
		(13 "F.Paste" user "Package Geometry/Pastemask Top")
		(15 "B.Paste" user "Package Geometry/Pastemask Bottom")
		(5 "F.SilkS" user "Ref Des/Silkscreen Top")
		(7 "B.SilkS" user "Ref Des/Silkscreen Bottom")
		(1 "F.Mask" user "Board Geometry/Soldermask Top")
		(3 "B.Mask" user "Board Geometry/Soldermask Bottom")
		(17 "Dwgs.User" user "User.Drawings")
		(19 "Cmts.User" user "User.Comments")
		(21 "Eco1.User" user "User.Eco1")
		(23 "Eco2.User" user "User.Eco2")
		(25 "Edge.Cuts" user "Board Geometry/Outline")
		(27 "Margin" user)
		(31 "F.CrtYd" user "Package Geometry/Place Bound Top")
		(29 "B.CrtYd" user "Package Geometry/Place Bound Bottom")
		(35 "F.Fab" user "Ref Des/Assembly Top")
		(33 "B.Fab" user "Ref Des/Assembly Bottom")
	)
	(footprint ""
		(layer "B.Cu")
		(at 430.362106 -125.165612 90)
		(property "Reference" "PR4236"
			(at 0 0 90)
			(layer "B.SilkS")
			(hide yes)
			(effects
				(font
					(size 1.27 1.27)
				)
				(justify mirror)
			)
		)
		(property "Value" ""
			(at 0 0 90)
			(layer "B.Fab")
			(effects
				(font
					(size 1.27 1.27)
				)
				(justify mirror)
			)
		)
		(duplicate_pad_numbers_are_jumpers no)
		(fp_line
			(start 0.7874 -0.4064)
			(end -0.7874 -0.4064)
			(stroke
				(width 0.1524)
				(type default)
			)
			(layer "B.SilkS")
		)
		(fp_line
			(start -0.7874 -0.4064)
			(end -0.7874 0.4064)
			(stroke
				(width 0.1524)
				(type default)
			)
			(layer "B.SilkS")
		)
		(fp_line
			(start 0.7874 0.4064)
			(end 0.7874 -0.4064)
			(stroke
				(width 0.1524)
				(type default)
			)
			(layer "B.SilkS")
		)
		(fp_line
			(start -0.7874 0.4064)
			(end 0.7874 0.4064)
			(stroke
				(width 0.1524)
				(type default)
			)
			(layer "B.SilkS")
		)
		(fp_line
			(start 0.67945 -0.305054)
			(end 0.12065 -0.305054)
			(stroke
				(width 0.1)
				(type default)
			)
			(layer "B.Fab")
		)
		(fp_line
			(start 0.12065 -0.305054)
			(end 0.12065 -0.2794)
			(stroke
				(width 0.1)
				(type default)
			)
			(layer "B.Fab")
		)
		(fp_line
			(start -0.12065 -0.3048)
			(end -0.67945 -0.3048)
			(stroke
				(width 0.1)
				(type default)
			)
			(layer "B.Fab")
		)
		(fp_line
			(start -0.67945 -0.3048)
			(end -0.67945 0.3048)
			(stroke
				(width 0.1)
				(type default)
			)
			(layer "B.Fab")
		)
		(fp_line
			(start 0.12065 -0.2794)
			(end -0.12065 -0.2794)
			(stroke
				(width 0.1)
				(type default)
			)
			(layer "B.Fab")
		)
		(fp_line
			(start -0.12065 -0.2794)
			(end -0.12065 -0.3048)
			(stroke
				(width 0.1)
				(type default)
			)
			(layer "B.Fab")
		)
		(fp_line
			(start 0.12065 0.2794)
			(end 0.12065 0.3048)
			(stroke
				(width 0.1)
				(type default)
			)
			(layer "B.Fab")
		)
		(fp_line
			(start -0.120396 0.2794)
			(end 0.12065 0.2794)
			(stroke
				(width 0.1)
				(type default)
			)
			(layer "B.Fab")
		)
		(fp_line
			(start 0.67945 0.3048)
			(end 0.67945 -0.305054)
			(stroke
				(width 0.1)
				(type default)
			)
			(layer "B.Fab")
		)
		(fp_line
			(start 0.12065 0.3048)
			(end 0.67945 0.3048)
			(stroke
				(width 0.1)
				(type default)
			)
			(layer "B.Fab")
		)
		(fp_line
			(start -0.120396 0.3048)
			(end -0.120396 0.2794)
			(stroke
				(width 0.1)
				(type default)
			)
			(layer "B.Fab")
		)
		(fp_line
			(start -0.67945 0.3048)
			(end -0.120396 0.3048)
			(stroke
				(width 0.1)
				(type default)
			)
			(layer "B.Fab")
		)
		(pad "1" smd circle
			(at 0.40005 0 270)
			(size 0 0)
			(layers "B.Cu" "B.Mask" "B.Paste")
			(net "NC_PVCCD_HV_CPU0_ACSP8")
		)
		(pad "2" smd circle
			(at -0.40005 0 270)
			(size 0 0)
			(layers "B.Cu" "B.Mask" "B.Paste")
			(net "GND")
		)
	)
	(footprint ""
		(layer "B.Cu")
		(at 418.395404 -319.402968 180)
		(property "Reference" "R885"
			(at 0 0 0)
			(layer "B.SilkS")
			(hide yes)
			(effects
				(font
					(size 1.27 1.27)
				)
				(justify mirror)
			)
		)
		(property "Value" ""
			(at 0 0 0)
			(layer "B.Fab")
			(effects
				(font
					(size 1.27 1.27)
				)
				(justify mirror)
			)
		)
		(duplicate_pad_numbers_are_jumpers no)
		(fp_line
			(start 0.7874 0.4064)
			(end 0.7874 -0.4064)
			(stroke
				(width 0.1524)
				(type default)
			)
			(layer "B.SilkS")
		)
		(fp_line
			(start 0.7874 -0.4064)
			(end -0.7874 -0.4064)
			(stroke
				(width 0.1524)
				(type default)
			)
			(layer "B.SilkS")
		)
		(fp_line
			(start -0.7874 0.4064)
			(end 0.7874 0.4064)
			(stroke
				(width 0.1524)
				(type default)
			)
			(layer "B.SilkS")
		)
		(fp_line
			(start -0.7874 -0.4064)
			(end -0.7874 0.4064)
			(stroke
				(width 0.1524)
				(type default)
			)
			(layer "B.SilkS")
		)
		(fp_line
			(start 0.67945 0.3048)
			(end 0.67945 -0.305054)
			(stroke
				(width 0.1)
				(type default)
			)
			(layer "B.Fab")
		)
		(fp_line
			(start 0.67945 -0.305054)
			(end 0.12065 -0.305054)
			(stroke
				(width 0.1)
				(type default)
			)
			(layer "B.Fab")
		)
		(fp_line
			(start 0.12065 0.3048)
			(end 0.67945 0.3048)
			(stroke
				(width 0.1)
				(type default)
			)
			(layer "B.Fab")
		)
		(fp_line
			(start 0.12065 0.2794)
			(end 0.12065 0.3048)
			(stroke
				(width 0.1)
				(type default)
			)
			(layer "B.Fab")
		)
		(fp_line
			(start 0.12065 -0.2794)
			(end -0.12065 -0.2794)
			(stroke
				(width 0.1)
				(type default)
			)
			(layer "B.Fab")
		)
		(fp_line
			(start 0.12065 -0.305054)
			(end 0.12065 -0.2794)
			(stroke
				(width 0.1)
				(type default)
			)
			(layer "B.Fab")
		)
		(fp_line
			(start -0.120396 0.3048)
			(end -0.120396 0.2794)
			(stroke
				(width 0.1)
				(type default)
			)
			(layer "B.Fab")
		)
		(fp_line
			(start -0.120396 0.2794)
			(end 0.12065 0.2794)
			(stroke
				(width 0.1)
				(type default)
			)
			(layer "B.Fab")
		)
		(fp_line
			(start -0.12065 -0.2794)
			(end -0.12065 -0.3048)
			(stroke
				(width 0.1)
				(type default)
			)
			(layer "B.Fab")
		)
		(fp_line
			(start -0.12065 -0.3048)
			(end -0.67945 -0.3048)
			(stroke
				(width 0.1)
				(type default)
			)
			(layer "B.Fab")
		)
		(fp_line
			(start -0.67945 0.3048)
			(end -0.120396 0.3048)
			(stroke
				(width 0.1)
				(type default)
			)
			(layer "B.Fab")
		)
		(fp_line
			(start -0.67945 -0.3048)
			(end -0.67945 0.3048)
			(stroke
				(width 0.1)
				(type default)
			)
			(layer "B.Fab")
		)
		(pad "1" smd circle
			(at 0.40005 0)
			(size 0 0)
			(layers "B.Cu" "B.Mask" "B.Paste")
			(net "PWRGD_CHE_CPU0_DIMM1")
		)
		(pad "2" smd circle
			(at -0.40005 0)
			(size 0 0)
			(layers "B.Cu" "B.Mask" "B.Paste")
			(net "PWRGD_FAIL_CPU0_EF")
		)
	)
)
